(kicad_pcb
	(version 20260206)
	(generator "pcbnew")
	(generator_version "10.0")
	(general
		(thickness 1.6)
		(legacy_teardrops no)
	)
	(paper "A4")
	(title_block
		(title "Bryce Canyon_R.DPB_16317-1_OCP.brd")
		(comment 1 "Bryce Canyon / footprints 1541-1547 of 2099")
	)
	(layers
		(0 "F.Cu" signal "TOP")
		(4 "In1.Cu" signal "L2GND")
		(6 "In2.Cu" signal "L3")
		(8 "In3.Cu" signal "L4VCC")
		(10 "In4.Cu" signal "L5VCC")
		(12 "In5.Cu" signal "L6")
		(14 "In6.Cu" signal "L7GND")
		(2 "B.Cu" signal "BOTTOM")
		(9 "F.Adhes" user "F.Adhesive")
		(11 "B.Adhes" user "B.Adhesive")
		(13 "F.Paste" user "Package Geometry/Pastemask Top")
		(15 "B.Paste" user "Package Geometry/Pastemask Bottom")
		(5 "F.SilkS" user "Ref Des/Silkscreen Top")
		(7 "B.SilkS" user "Ref Des/Silkscreen Bottom")
		(1 "F.Mask" user "Board Geometry/Soldermask Top")
		(3 "B.Mask" user "Board Geometry/Soldermask Bottom")
		(17 "Dwgs.User" user "User.Drawings")
		(19 "Cmts.User" user "User.Comments")
		(21 "Eco1.User" user "User.Eco1")
		(23 "Eco2.User" user "User.Eco2")
		(25 "Edge.Cuts" user "Board Geometry/Outline")
		(27 "Margin" user)
		(31 "F.CrtYd" user "Package Geometry/Place Bound Top")
		(29 "B.CrtYd" user "Package Geometry/Place Bound Bottom")
		(35 "F.Fab" user "Ref Des/Assembly Top")
		(33 "B.Fab" user "Ref Des/Assembly Bottom")
	)
	(footprint ""
		(layer "F.Cu")
		(at 424.434 -37.846 180)
		(property "Reference" "C459"
			(at 0 0 180)
			(layer "F.SilkS")
			(hide yes)
			(effects
				(font
					(size 1.27 1.27)
				)
			)
		)
		(property "Value" "SC1U16V3KX-5GP"
			(at 0 -2.8194 180)
			(unlocked yes)
			(layer "F.Fab")
			(hide yes)
			(effects
				(font
					(size 1.016 1.016)
					(thickness 0.1524)
				)
			)
		)
		(property "Device Type" "C603H36"
			(at 0 -4.3434 180)
			(unlocked yes)
			(layer "F.Fab")
			(hide yes)
			(effects
				(font
					(size 1.016 1.016)
					(thickness 0.1524)
				)
			)
		)
		(duplicate_pad_numbers_are_jumpers no)
		(fp_line
			(start 0.508 0)
			(end -0.508 0)
			(stroke
				(width 0.2032)
				(type default)
			)
			(layer "F.SilkS")
		)
		(fp_rect
			(start -0.5842 1.3335)
			(end 0.5842 -1.3335)
			(stroke
				(width 0)
				(type default)
			)
			(fill no)
			(layer "F.CrtYd")
		)
		(fp_rect
			(start -0.5842 1.3335)
			(end 0.5842 -1.3335)
			(stroke
				(width 0)
				(type default)
			)
			(fill no)
			(layer "F.Fab")
		)
		(pad "1" smd custom
			(at 0 -0.762 180)
			(size 0.2159 0.2159)
			(layers "F.Cu" "F.Mask" "F.Paste")
			(net "P5V_HDD33")
			(options
				(clearance outline)
				(anchor circle)
			)
			(primitives
				(gr_poly
					(pts
						(arc
							(start -0.3302 -0.4318)
							(mid -0.402042 -0.402042)
							(end -0.4318 -0.3302)
						)
						(arc
							(start -0.4318 0.3302)
							(mid -0.402042 0.402042)
							(end -0.3302 0.4318)
						)
						(arc
							(start 0.3302 0.4318)
							(mid 0.402042 0.402042)
							(end 0.4318 0.3302)
						)
						(arc
							(start 0.4318 -0.3302)
							(mid 0.402042 -0.402042)
							(end 0.3302 -0.4318)
						)
					)
					(width 0)
					(fill yes)
				)
			)
		)
		(pad "2" smd custom
			(at 0 0.762 180)
			(size 0.2159 0.2159)
			(layers "F.Cu" "F.Mask" "F.Paste")
			(net "GND")
			(options
				(clearance outline)
				(anchor circle)
			)
			(primitives
				(gr_poly
					(pts
						(arc
							(start -0.3302 -0.4318)
							(mid -0.402042 -0.402042)
							(end -0.4318 -0.3302)
						)
						(arc
							(start -0.4318 0.3302)
							(mid -0.402042 0.402042)
							(end -0.3302 0.4318)
						)
						(arc
							(start 0.3302 0.4318)
							(mid 0.402042 0.402042)
							(end 0.4318 0.3302)
						)
						(arc
							(start 0.4318 -0.3302)
							(mid 0.402042 -0.402042)
							(end 0.3302 -0.4318)
						)
					)
					(width 0)
					(fill yes)
				)
			)
		)
	)
	(footprint ""
		(layer "F.Cu")
		(at 137.030968 -99.874578 90)
		(property "Reference" "Q265"
			(at 0 0 90)
			(layer "F.SilkS")
			(hide yes)
			(effects
				(font
					(size 1.27 1.27)
				)
			)
		)
		(property "Value" "SSM3K324R-GP"
			(at 0.127 -8.9662 90)
			(unlocked yes)
			(layer "F.Fab")
			(hide yes)
			(effects
				(font
					(size 1.016 1.016)
					(thickness 0.1524)
				)
			)
		)
		(property "Device Type" "SOT23DGS2D4H35"
			(at 0.127 -10.4902 90)
			(unlocked yes)
			(layer "F.Fab")
			(hide yes)
			(effects
				(font
					(size 1.016 1.016)
					(thickness 0.1524)
				)
			)
		)
		(duplicate_pad_numbers_are_jumpers no)
		(fp_line
			(start 1.651 -1.778)
			(end -1.651 -1.778)
			(stroke
				(width 0.1524)
				(type default)
			)
			(layer "F.SilkS")
		)
		(fp_line
			(start -1.651 -1.778)
			(end -1.651 1.778)
			(stroke
				(width 0.1524)
				(type default)
			)
			(layer "F.SilkS")
		)
		(fp_line
			(start 1.651 1.778)
			(end 1.651 -1.778)
			(stroke
				(width 0.1524)
				(type default)
			)
			(layer "F.SilkS")
		)
		(fp_line
			(start -1.651 1.778)
			(end 1.651 1.778)
			(stroke
				(width 0.1524)
				(type default)
			)
			(layer "F.SilkS")
		)
		(fp_poly
			(pts
				(xy -1.778 1.8796) (xy -1.778 -1.8796) (xy 1.778 -1.8796) (xy 1.778 1.8796)
			)
			(stroke
				(width 0)
				(type default)
			)
			(fill no)
			(layer "F.CrtYd")
		)
		(fp_poly
			(pts
				(xy -1.778 1.8796) (xy -1.778 -1.8796) (xy 1.778 -1.8796) (xy 1.778 1.8796)
			)
			(stroke
				(width 0)
				(type default)
			)
			(fill no)
			(layer "F.Fab")
		)
		(pad "D" smd custom
			(at 0 -0.9525 90)
			(size 0.1905 0.1905)
			(layers "F.Cu" "F.Mask" "F.Paste")
			(net "DRV_ACT_16_N")
			(options
				(clearance outline)
				(anchor circle)
			)
			(primitives
				(gr_poly
					(pts
						(arc
							(start -0.1778 0.5715)
							(mid -0.321484 0.511984)
							(end -0.381 0.3683)
						)
						(arc
							(start -0.381 -0.3683)
							(mid -0.321484 -0.511984)
							(end -0.1778 -0.5715)
						)
						(arc
							(start 0.1778 -0.5715)
							(mid 0.321484 -0.511984)
							(end 0.381 -0.3683)
						)
						(arc
							(start 0.381 0.3683)
							(mid 0.321484 0.511984)
							(end 0.1778 0.5715)
						)
					)
					(width 0)
					(fill yes)
				)
			)
		)
		(pad "G" smd custom
			(at -0.98425 0.9525 90)
			(size 0.1905 0.1905)
			(layers "F.Cu" "F.Mask" "F.Paste")
			(net "DRIVE_B_16_ACT")
			(options
				(clearance outline)
				(anchor circle)
			)
			(primitives
				(gr_poly
					(pts
						(arc
							(start -0.1778 0.5715)
							(mid -0.321484 0.511984)
							(end -0.381 0.3683)
						)
						(arc
							(start -0.381 -0.3683)
							(mid -0.321484 -0.511984)
							(end -0.1778 -0.5715)
						)
						(arc
							(start 0.1778 -0.5715)
							(mid 0.321484 -0.511984)
							(end 0.381 -0.3683)
						)
						(arc
							(start 0.381 0.3683)
							(mid 0.321484 0.511984)
							(end 0.1778 0.5715)
						)
					)
					(width 0)
					(fill yes)
				)
			)
		)
		(pad "S" smd custom
			(at 0.98425 0.9525 90)
			(size 0.1905 0.1905)
			(layers "F.Cu" "F.Mask" "F.Paste")
			(net "GND")
			(options
				(clearance outline)
				(anchor circle)
			)
			(primitives
				(gr_poly
					(pts
						(arc
							(start -0.1778 0.5715)
							(mid -0.321484 0.511984)
							(end -0.381 0.3683)
						)
						(arc
							(start -0.381 -0.3683)
							(mid -0.321484 -0.511984)
							(end -0.1778 -0.5715)
						)
						(arc
							(start 0.1778 -0.5715)
							(mid 0.321484 -0.511984)
							(end 0.381 -0.3683)
						)
						(arc
							(start 0.381 0.3683)
							(mid 0.321484 0.511984)
							(end 0.1778 0.5715)
						)
					)
					(width 0)
					(fill yes)
				)
			)
		)
	)
	(footprint ""
		(layer "F.Cu")
		(at 468.122 -252.095 180)
		(property "Reference" "R346"
			(at 0 0 180)
			(layer "F.SilkS")
			(hide yes)
			(effects
				(font
					(size 1.27 1.27)
				)
			)
		)
		(property "Value" "200KR2F-L-GP"
			(at 0.064008 -3.993896 180)
			(unlocked yes)
			(layer "F.Fab")
			(hide yes)
			(effects
				(font
					(size 1.016 1.016)
					(thickness 0.1524)
				)
			)
		)
		(property "Device Type" "R402H16"
			(at 0.064008 -5.517896 180)
			(unlocked yes)
			(layer "F.Fab")
			(hide yes)
			(effects
				(font
					(size 1.016 1.016)
					(thickness 0.1524)
				)
			)
		)
		(duplicate_pad_numbers_are_jumpers no)
		(fp_line
			(start 0.508 -0.9398)
			(end -0.508 -0.9398)
			(stroke
				(width 0.1524)
				(type default)
			)
			(layer "F.SilkS")
		)
		(fp_line
			(start -0.508 -0.9398)
			(end -0.508 0.9398)
			(stroke
				(width 0.1524)
				(type default)
			)
			(layer "F.SilkS")
		)
		(fp_rect
			(start -0.508 0.9398)
			(end 0.508 -0.9398)
			(stroke
				(width 0)
				(type default)
			)
			(fill no)
			(layer "F.CrtYd")
		)
		(fp_rect
			(start -0.508 0.9398)
			(end 0.508 -0.9398)
			(stroke
				(width 0)
				(type default)
			)
			(fill no)
			(layer "F.Fab")
		)
		(pad "1" smd custom
			(at 0 -0.4445 180)
			(size 0.1397 0.1397)
			(layers "F.Cu" "F.Mask" "F.Paste")
			(net "SW_HDD_R11")
			(options
				(clearance outline)
				(anchor circle)
			)
			(primitives
				(gr_poly
					(pts
						(arc
							(start -0.1778 -0.2794)
							(mid -0.249642 -0.249642)
							(end -0.2794 -0.1778)
						)
						(arc
							(start -0.2794 0.1778)
							(mid -0.249642 0.249642)
							(end -0.1778 0.2794)
						)
						(arc
							(start 0.1778 0.2794)
							(mid 0.249642 0.249642)
							(end 0.2794 0.1778)
						)
						(arc
							(start 0.2794 -0.1778)
							(mid 0.249642 -0.249642)
							(end 0.1778 -0.2794)
						)
					)
					(width 0)
					(fill yes)
				)
			)
		)
		(pad "2" smd custom
			(at 0 0.4445 180)
			(size 0.1397 0.1397)
			(layers "F.Cu" "F.Mask" "F.Paste")
			(net "SW_HDD_N11")
			(options
				(clearance outline)
				(anchor circle)
			)
			(primitives
				(gr_poly
					(pts
						(arc
							(start -0.1778 -0.2794)
							(mid -0.249642 -0.249642)
							(end -0.2794 -0.1778)
						)
						(arc
							(start -0.2794 0.1778)
							(mid -0.249642 0.249642)
							(end -0.1778 0.2794)
						)
						(arc
							(start 0.1778 0.2794)
							(mid 0.249642 0.249642)
							(end 0.2794 0.1778)
						)
						(arc
							(start 0.2794 -0.1778)
							(mid 0.249642 -0.249642)
							(end 0.1778 -0.2794)
						)
					)
					(width 0)
					(fill yes)
				)
			)
		)
	)
	(footprint ""
		(layer "F.Cu")
		(at 47.402496 -357.8352 90)
		(property "Reference" "R150"
			(at 0 0 90)
			(layer "F.SilkS")
			(hide yes)
			(effects
				(font
					(size 1.27 1.27)
				)
			)
		)
		(property "Value" "300KR2F-GP"
			(at 0.064008 -3.993896 90)
			(unlocked yes)
			(layer "F.Fab")
			(hide yes)
			(effects
				(font
					(size 1.016 1.016)
					(thickness 0.1524)
				)
			)
		)
		(property "Device Type" "R402H16"
			(at 0.064008 -5.517896 90)
			(unlocked yes)
			(layer "F.Fab")
			(hide yes)
			(effects
				(font
					(size 1.016 1.016)
					(thickness 0.1524)
				)
			)
		)
		(duplicate_pad_numbers_are_jumpers no)
		(fp_line
			(start 0.508 -0.9398)
			(end -0.508 -0.9398)
			(stroke
				(width 0.1524)
				(type default)
			)
			(layer "F.SilkS")
		)
		(fp_line
			(start -0.508 -0.9398)
			(end -0.508 0.9398)
			(stroke
				(width 0.1524)
				(type default)
			)
			(layer "F.SilkS")
		)
		(fp_rect
			(start -0.508 0.9398)
			(end 0.508 -0.9398)
			(stroke
				(width 0)
				(type default)
			)
			(fill no)
			(layer "F.CrtYd")
		)
		(fp_rect
			(start -0.508 0.9398)
			(end 0.508 -0.9398)
			(stroke
				(width 0)
				(type default)
			)
			(fill no)
			(layer "F.Fab")
		)
		(pad "1" smd custom
			(at 0 -0.4445 90)
			(size 0.1397 0.1397)
			(layers "F.Cu" "F.Mask" "F.Paste")
			(net "GATE_FAN0_R")
			(options
				(clearance outline)
				(anchor circle)
			)
			(primitives
				(gr_poly
					(pts
						(arc
							(start -0.1778 -0.2794)
							(mid -0.249642 -0.249642)
							(end -0.2794 -0.1778)
						)
						(arc
							(start -0.2794 0.1778)
							(mid -0.249642 0.249642)
							(end -0.1778 0.2794)
						)
						(arc
							(start 0.1778 0.2794)
							(mid 0.249642 0.249642)
							(end 0.2794 0.1778)
						)
						(arc
							(start 0.2794 -0.1778)
							(mid 0.249642 -0.249642)
							(end 0.1778 -0.2794)
						)
					)
					(width 0)
					(fill yes)
				)
			)
		)
		(pad "2" smd custom
			(at 0 0.4445 90)
			(size 0.1397 0.1397)
			(layers "F.Cu" "F.Mask" "F.Paste")
			(net "P12V_IN")
			(options
				(clearance outline)
				(anchor circle)
			)
			(primitives
				(gr_poly
					(pts
						(arc
							(start -0.1778 -0.2794)
							(mid -0.249642 -0.249642)
							(end -0.2794 -0.1778)
						)
						(arc
							(start -0.2794 0.1778)
							(mid -0.249642 0.249642)
							(end -0.1778 0.2794)
						)
						(arc
							(start 0.1778 0.2794)
							(mid 0.249642 0.249642)
							(end 0.2794 0.1778)
						)
						(arc
							(start 0.2794 -0.1778)
							(mid 0.249642 -0.249642)
							(end 0.1778 -0.2794)
						)
					)
					(width 0)
					(fill yes)
				)
			)
		)
	)
	(footprint ""
		(layer "F.Cu")
		(at 467.741 -135.509 90)
		(property "Reference" "R613"
			(at 0 0 90)
			(layer "F.SilkS")
			(hide yes)
			(effects
				(font
					(size 1.27 1.27)
				)
			)
		)
		(property "Value" "4K7R2J-2-GP"
			(at 0.064008 -3.993896 90)
			(unlocked yes)
			(layer "F.Fab")
			(hide yes)
			(effects
				(font
					(size 1.016 1.016)
					(thickness 0.1524)
				)
			)
		)
		(property "Device Type" "R402H16"
			(at 0.064008 -5.517896 90)
			(unlocked yes)
			(layer "F.Fab")
			(hide yes)
			(effects
				(font
					(size 1.016 1.016)
					(thickness 0.1524)
				)
			)
		)
		(duplicate_pad_numbers_are_jumpers no)
		(fp_line
			(start 0.508 -0.9398)
			(end -0.508 -0.9398)
			(stroke
				(width 0.1524)
				(type default)
			)
			(layer "F.SilkS")
		)
		(fp_line
			(start -0.508 -0.9398)
			(end -0.508 0.9398)
			(stroke
				(width 0.1524)
				(type default)
			)
			(layer "F.SilkS")
		)
		(fp_rect
			(start -0.508 0.9398)
			(end 0.508 -0.9398)
			(stroke
				(width 0)
				(type default)
			)
			(fill no)
			(layer "F.CrtYd")
		)
		(fp_rect
			(start -0.508 0.9398)
			(end 0.508 -0.9398)
			(stroke
				(width 0)
				(type default)
			)
			(fill no)
			(layer "F.Fab")
		)
		(pad "1" smd custom
			(at 0 -0.4445 90)
			(size 0.1397 0.1397)
			(layers "F.Cu" "F.Mask" "F.Paste")
			(net "P12V_B")
			(options
				(clearance outline)
				(anchor circle)
			)
			(primitives
				(gr_poly
					(pts
						(arc
							(start -0.1778 -0.2794)
							(mid -0.249642 -0.249642)
							(end -0.2794 -0.1778)
						)
						(arc
							(start -0.2794 0.1778)
							(mid -0.249642 0.249642)
							(end -0.1778 0.2794)
						)
						(arc
							(start 0.1778 0.2794)
							(mid 0.249642 0.249642)
							(end 0.2794 0.1778)
						)
						(arc
							(start 0.2794 -0.1778)
							(mid 0.249642 -0.249642)
							(end 0.1778 -0.2794)
						)
					)
					(width 0)
					(fill yes)
				)
			)
		)
		(pad "2" smd custom
			(at 0 0.4445 90)
			(size 0.1397 0.1397)
			(layers "F.Cu" "F.Mask" "F.Paste")
			(net "SW_HDD_R23")
			(options
				(clearance outline)
				(anchor circle)
			)
			(primitives
				(gr_poly
					(pts
						(arc
							(start -0.1778 -0.2794)
							(mid -0.249642 -0.249642)
							(end -0.2794 -0.1778)
						)
						(arc
							(start -0.2794 0.1778)
							(mid -0.249642 0.249642)
							(end -0.1778 0.2794)
						)
						(arc
							(start 0.1778 0.2794)
							(mid 0.249642 0.249642)
							(end 0.2794 0.1778)
						)
						(arc
							(start 0.2794 -0.1778)
							(mid 0.249642 -0.249642)
							(end 0.1778 -0.2794)
						)
					)
					(width 0)
					(fill yes)
				)
			)
		)
	)
	(footprint ""
		(layer "F.Cu")
		(at 51.5112 -9.9568)
		(property "Reference" "R660"
			(at 0 0 0)
			(layer "F.SilkS")
			(hide yes)
			(effects
				(font
					(size 1.27 1.27)
				)
			)
		)
		(property "Value" "300KR2F-GP"
			(at 0.064008 -3.993896 0)
			(unlocked yes)
			(layer "F.Fab")
			(hide yes)
			(effects
				(font
					(size 1.016 1.016)
					(thickness 0.1524)
				)
			)
		)
		(property "Device Type" "R402H16"
			(at 0.064008 -5.517896 0)
			(unlocked yes)
			(layer "F.Fab")
			(hide yes)
			(effects
				(font
					(size 1.016 1.016)
					(thickness 0.1524)
				)
			)
		)
		(duplicate_pad_numbers_are_jumpers no)
		(fp_line
			(start -0.508 -0.9398)
			(end -0.508 0.9398)
			(stroke
				(width 0.1524)
				(type default)
			)
			(layer "F.SilkS")
		)
		(fp_line
			(start 0.508 -0.9398)
			(end -0.508 -0.9398)
			(stroke
				(width 0.1524)
				(type default)
			)
			(layer "F.SilkS")
		)
		(fp_rect
			(start -0.508 0.9398)
			(end 0.508 -0.9398)
			(stroke
				(width 0)
				(type default)
			)
			(fill no)
			(layer "F.CrtYd")
		)
		(fp_rect
			(start -0.508 0.9398)
			(end 0.508 -0.9398)
			(stroke
				(width 0)
				(type default)
			)
			(fill no)
			(layer "F.Fab")
		)
		(pad "1" smd custom
			(at 0 -0.4445)
			(size 0.1397 0.1397)
			(layers "F.Cu" "F.Mask" "F.Paste")
			(net "SW_HDD_N25")
			(options
				(clearance outline)
				(anchor circle)
			)
			(primitives
				(gr_poly
					(pts
						(arc
							(start -0.1778 -0.2794)
							(mid -0.249642 -0.249642)
							(end -0.2794 -0.1778)
						)
						(arc
							(start -0.2794 0.1778)
							(mid -0.249642 0.249642)
							(end -0.1778 0.2794)
						)
						(arc
							(start 0.1778 0.2794)
							(mid 0.249642 0.249642)
							(end 0.2794 0.1778)
						)
						(arc
							(start 0.2794 -0.1778)
							(mid 0.249642 -0.249642)
							(end 0.1778 -0.2794)
						)
					)
					(width 0)
					(fill yes)
				)
			)
		)
		(pad "2" smd custom
			(at 0 0.4445)
			(size 0.1397 0.1397)
			(layers "F.Cu" "F.Mask" "F.Paste")
			(net "P12V_B")
			(options
				(clearance outline)
				(anchor circle)
			)
			(primitives
				(gr_poly
					(pts
						(arc
							(start -0.1778 -0.2794)
							(mid -0.249642 -0.249642)
							(end -0.2794 -0.1778)
						)
						(arc
							(start -0.2794 0.1778)
							(mid -0.249642 0.249642)
							(end -0.1778 0.2794)
						)
						(arc
							(start 0.1778 0.2794)
							(mid 0.249642 0.249642)
							(end 0.2794 0.1778)
						)
						(arc
							(start 0.2794 -0.1778)
							(mid 0.249642 -0.249642)
							(end 0.1778 -0.2794)
						)
					)
					(width 0)
					(fill yes)
				)
			)
		)
	)
	(footprint ""
		(layer "F.Cu")
		(at 331.47 -44.958 180)
		(property "Reference" "C424"
			(at 0 0 180)
			(layer "F.SilkS")
			(hide yes)
			(effects
				(font
					(size 1.27 1.27)
				)
			)
		)
		(property "Value" "SC4D7U25V5KX-1-GP"
			(at -0.0762 -6.1214 180)
			(unlocked yes)
			(layer "F.Fab")
			(hide yes)
			(effects
				(font
					(size 1.016 1.016)
					(thickness 0.1524)
				)
			)
		)
		(property "Device Type" "C805H58"
			(at -0.0762 -8.1534 180)
			(unlocked yes)
			(layer "F.Fab")
			(hide yes)
			(effects
				(font
					(size 1.016 1.016)
					(thickness 0.1524)
				)
			)
		)
		(duplicate_pad_numbers_are_jumpers no)
		(fp_line
			(start 0.635 0)
			(end -0.635 0)
			(stroke
				(width 0.508)
				(type default)
			)
			(layer "F.SilkS")
		)
		(fp_rect
			(start -0.9652 1.778)
			(end 0.9652 -1.778)
			(stroke
				(width 0)
				(type default)
			)
			(fill no)
			(layer "F.CrtYd")
		)
		(fp_poly
			(pts
				(xy -0.9652 -1.778) (xy 0.9652 -1.778) (xy 0.9652 1.778) (xy -0.9652 1.778)
			)
			(stroke
				(width 0)
				(type default)
			)
			(fill no)
			(layer "F.Fab")
		)
		(pad "1" smd rect
			(at 0 -0.9652 180)
			(size 1.397 1.143)
			(layers "F.Cu" "F.Mask" "F.Paste")
			(net "P12V_HDD30")
		)
		(pad "2" smd rect
			(at 0 0.9652 180)
			(size 1.397 1.143)
			(layers "F.Cu" "F.Mask" "F.Paste")
			(net "GND")
		)
	)
)
